(kicad_pcb
	(version 20260206)
	(generator "pcbnew")
	(generator_version "10.0")
	(general
		(thickness 1.6)
		(legacy_teardrops no)
	)
	(paper "A4")
	(title_block
		(title "Bryce Canyon_R.DPB_16317-1_OCP.brd")
		(comment 1 "Bryce Canyon / footprints 1789-1795 of 2099")
	)
	(layers
		(0 "F.Cu" signal "TOP")
		(4 "In1.Cu" signal "L2GND")
		(6 "In2.Cu" signal "L3")
		(8 "In3.Cu" signal "L4VCC")
		(10 "In4.Cu" signal "L5VCC")
		(12 "In5.Cu" signal "L6")
		(14 "In6.Cu" signal "L7GND")
		(2 "B.Cu" signal "BOTTOM")
		(9 "F.Adhes" user "F.Adhesive")
		(11 "B.Adhes" user "B.Adhesive")
		(13 "F.Paste" user "Package Geometry/Pastemask Top")
		(15 "B.Paste" user "Package Geometry/Pastemask Bottom")
		(5 "F.SilkS" user "Ref Des/Silkscreen Top")
		(7 "B.SilkS" user "Ref Des/Silkscreen Bottom")
		(1 "F.Mask" user "Board Geometry/Soldermask Top")
		(3 "B.Mask" user "Board Geometry/Soldermask Bottom")
		(17 "Dwgs.User" user "User.Drawings")
		(19 "Cmts.User" user "User.Comments")
		(21 "Eco1.User" user "User.Eco1")
		(23 "Eco2.User" user "User.Eco2")
		(25 "Edge.Cuts" user "Board Geometry/Outline")
		(27 "Margin" user)
		(31 "F.CrtYd" user "Package Geometry/Place Bound Top")
		(29 "B.CrtYd" user "Package Geometry/Place Bound Bottom")
		(35 "F.Fab" user "Ref Des/Assembly Top")
		(33 "B.Fab" user "Ref Des/Assembly Bottom")
	)
	(footprint ""
		(layer "F.Cu")
		(at 129.286 -374.523 -90)
		(property "Reference" "C524"
			(at 0 0 270)
			(layer "F.SilkS")
			(hide yes)
			(effects
				(font
					(size 1.27 1.27)
				)
			)
		)
		(property "Value" "SCD1U25V2KX-2-GP"
			(at 1.1811 -2.7051 270)
			(unlocked yes)
			(layer "F.Fab")
			(hide yes)
			(effects
				(font
					(size 1.016 1.016)
					(thickness 0.1524)
				)
			)
		)
		(property "Device Type" "C402H22"
			(at 1.1811 -4.2291 270)
			(unlocked yes)
			(layer "F.Fab")
			(hide yes)
			(effects
				(font
					(size 1.016 1.016)
					(thickness 0.1524)
				)
			)
		)
		(duplicate_pad_numbers_are_jumpers no)
		(fp_rect
			(start -0.4318 0.9525)
			(end 0.4318 -0.9525)
			(stroke
				(width 0)
				(type default)
			)
			(fill no)
			(layer "F.CrtYd")
		)
		(fp_rect
			(start -0.4318 0.9525)
			(end 0.4318 -0.9525)
			(stroke
				(width 0)
				(type default)
			)
			(fill no)
			(layer "F.Fab")
		)
		(pad "1" smd custom
			(at 0 -0.4445 270)
			(size 0.1524 0.1524)
			(layers "F.Cu" "F.Mask" "F.Paste")
			(net "FAN_1_TACH0")
			(options
				(clearance outline)
				(anchor circle)
			)
			(primitives
				(gr_poly
					(pts
						(arc
							(start 0.3048 -0.2032)
							(mid 0.275042 -0.275042)
							(end 0.2032 -0.3048)
						)
						(arc
							(start -0.2032 -0.3048)
							(mid -0.275042 -0.275042)
							(end -0.3048 -0.2032)
						)
						(arc
							(start -0.3048 0.2032)
							(mid -0.275042 0.275042)
							(end -0.2032 0.3048)
						)
						(arc
							(start 0.2032 0.3048)
							(mid 0.275042 0.275042)
							(end 0.3048 0.2032)
						)
					)
					(width 0)
					(fill yes)
				)
			)
		)
		(pad "2" smd custom
			(at 0 0.4445 270)
			(size 0.1524 0.1524)
			(layers "F.Cu" "F.Mask" "F.Paste")
			(net "GND")
			(options
				(clearance outline)
				(anchor circle)
			)
			(primitives
				(gr_poly
					(pts
						(arc
							(start 0.3048 -0.2032)
							(mid 0.275042 -0.275042)
							(end 0.2032 -0.3048)
						)
						(arc
							(start -0.2032 -0.3048)
							(mid -0.275042 -0.275042)
							(end -0.3048 -0.2032)
						)
						(arc
							(start -0.3048 0.2032)
							(mid -0.275042 0.275042)
							(end -0.2032 0.3048)
						)
						(arc
							(start 0.2032 0.3048)
							(mid 0.275042 0.275042)
							(end 0.3048 0.2032)
						)
					)
					(width 0)
					(fill yes)
				)
			)
		)
	)
	(footprint ""
		(layer "F.Cu")
		(at 381.2032 -146.2532)
		(property "Reference" "R534"
			(at 0 0 0)
			(layer "F.SilkS")
			(hide yes)
			(effects
				(font
					(size 1.27 1.27)
				)
			)
		)
		(property "Value" "220R3F-1-GP"
			(at -0.0254 -2.5146 0)
			(unlocked yes)
			(layer "F.Fab")
			(hide yes)
			(effects
				(font
					(size 1.016 1.016)
					(thickness 0.1524)
				)
			)
		)
		(property "Device Type" "R603H22"
			(at -0.0254 -4.0386 0)
			(unlocked yes)
			(layer "F.Fab")
			(hide yes)
			(effects
				(font
					(size 1.016 1.016)
					(thickness 0.1524)
				)
			)
		)
		(duplicate_pad_numbers_are_jumpers no)
		(fp_line
			(start -0.4826 0)
			(end -0.2032 0)
			(stroke
				(width 0.2032)
				(type default)
			)
			(layer "F.SilkS")
		)
		(fp_line
			(start 0.2032 0)
			(end 0.4826 0)
			(stroke
				(width 0.2032)
				(type default)
			)
			(layer "F.SilkS")
		)
		(fp_rect
			(start -0.5842 1.3335)
			(end 0.5842 -1.3335)
			(stroke
				(width 0)
				(type default)
			)
			(fill no)
			(layer "F.CrtYd")
		)
		(fp_rect
			(start -0.5842 1.3335)
			(end 0.5842 -1.3335)
			(stroke
				(width 0)
				(type default)
			)
			(fill no)
			(layer "F.Fab")
		)
		(pad "1" smd custom
			(at 0 -0.762)
			(size 0.2159 0.2159)
			(layers "F.Cu" "F.Mask" "F.Paste")
			(net "HDD_PRSNT_20")
			(options
				(clearance outline)
				(anchor circle)
			)
			(primitives
				(gr_poly
					(pts
						(arc
							(start -0.3302 -0.4318)
							(mid -0.402042 -0.402042)
							(end -0.4318 -0.3302)
						)
						(arc
							(start -0.4318 0.3302)
							(mid -0.402042 0.402042)
							(end -0.3302 0.4318)
						)
						(arc
							(start 0.3302 0.4318)
							(mid 0.402042 0.402042)
							(end 0.4318 0.3302)
						)
						(arc
							(start 0.4318 -0.3302)
							(mid 0.402042 -0.402042)
							(end 0.3302 -0.4318)
						)
					)
					(width 0)
					(fill yes)
				)
			)
		)
		(pad "2" smd custom
			(at 0 0.762)
			(size 0.2159 0.2159)
			(layers "F.Cu" "F.Mask" "F.Paste")
			(net "DRIVE_B_20_INS")
			(options
				(clearance outline)
				(anchor circle)
			)
			(primitives
				(gr_poly
					(pts
						(arc
							(start -0.3302 -0.4318)
							(mid -0.402042 -0.402042)
							(end -0.4318 -0.3302)
						)
						(arc
							(start -0.4318 0.3302)
							(mid -0.402042 0.402042)
							(end -0.3302 0.4318)
						)
						(arc
							(start 0.3302 0.4318)
							(mid 0.402042 0.402042)
							(end 0.4318 0.3302)
						)
						(arc
							(start 0.4318 -0.3302)
							(mid 0.402042 -0.402042)
							(end 0.3302 -0.4318)
						)
					)
					(width 0)
					(fill yes)
				)
			)
		)
	)
	(footprint ""
		(layer "F.Cu")
		(at 461.899 -243.586 180)
		(property "Reference" "R326"
			(at 0 0 180)
			(layer "F.SilkS")
			(hide yes)
			(effects
				(font
					(size 1.27 1.27)
				)
			)
		)
		(property "Value" "0R2J-2-GP"
			(at 0.064008 -3.993896 180)
			(unlocked yes)
			(layer "F.Fab")
			(hide yes)
			(effects
				(font
					(size 1.016 1.016)
					(thickness 0.1524)
				)
			)
		)
		(property "Device Type" "R402H16"
			(at 0.064008 -5.517896 180)
			(unlocked yes)
			(layer "F.Fab")
			(hide yes)
			(effects
				(font
					(size 1.016 1.016)
					(thickness 0.1524)
				)
			)
		)
		(duplicate_pad_numbers_are_jumpers no)
		(fp_line
			(start 0.508 -0.9398)
			(end -0.508 -0.9398)
			(stroke
				(width 0.1524)
				(type default)
			)
			(layer "F.SilkS")
		)
		(fp_line
			(start -0.508 -0.9398)
			(end -0.508 0.9398)
			(stroke
				(width 0.1524)
				(type default)
			)
			(layer "F.SilkS")
		)
		(fp_rect
			(start -0.508 0.9398)
			(end 0.508 -0.9398)
			(stroke
				(width 0)
				(type default)
			)
			(fill no)
			(layer "F.CrtYd")
		)
		(fp_rect
			(start -0.508 0.9398)
			(end 0.508 -0.9398)
			(stroke
				(width 0)
				(type default)
			)
			(fill no)
			(layer "F.Fab")
		)
		(pad "1" smd custom
			(at 0 -0.4445 180)
			(size 0.1397 0.1397)
			(layers "F.Cu" "F.Mask" "F.Paste")
			(net "DRIVE_B_10_PWR")
			(options
				(clearance outline)
				(anchor circle)
			)
			(primitives
				(gr_poly
					(pts
						(arc
							(start -0.1778 -0.2794)
							(mid -0.249642 -0.249642)
							(end -0.2794 -0.1778)
						)
						(arc
							(start -0.2794 0.1778)
							(mid -0.249642 0.249642)
							(end -0.1778 0.2794)
						)
						(arc
							(start 0.1778 0.2794)
							(mid 0.249642 0.249642)
							(end 0.2794 0.1778)
						)
						(arc
							(start 0.2794 -0.1778)
							(mid 0.249642 -0.249642)
							(end 0.1778 -0.2794)
						)
					)
					(width 0)
					(fill yes)
				)
			)
		)
		(pad "2" smd custom
			(at 0 0.4445 180)
			(size 0.1397 0.1397)
			(layers "F.Cu" "F.Mask" "F.Paste")
			(net "SW_PWR_R_HDD10")
			(options
				(clearance outline)
				(anchor circle)
			)
			(primitives
				(gr_poly
					(pts
						(arc
							(start -0.1778 -0.2794)
							(mid -0.249642 -0.249642)
							(end -0.2794 -0.1778)
						)
						(arc
							(start -0.2794 0.1778)
							(mid -0.249642 0.249642)
							(end -0.1778 0.2794)
						)
						(arc
							(start 0.1778 0.2794)
							(mid 0.249642 0.249642)
							(end 0.2794 0.1778)
						)
						(arc
							(start 0.2794 -0.1778)
							(mid 0.249642 -0.249642)
							(end 0.1778 -0.2794)
						)
					)
					(width 0)
					(fill yes)
				)
			)
		)
	)
	(footprint ""
		(layer "F.Cu")
		(at 115.062 -249.555 180)
		(property "Reference" "Q11"
			(at 0 0 180)
			(layer "F.SilkS")
			(hide yes)
			(effects
				(font
					(size 1.27 1.27)
				)
			)
		)
		(property "Value" "2N7002KDW-GP"
			(at -2.3622 -8.2042 180)
			(unlocked yes)
			(layer "F.Fab")
			(hide yes)
			(effects
				(font
					(size 1.016 1.016)
					(thickness 0.1524)
				)
			)
		)
		(property "Device Type" "SOT-363H44"
			(at -2.3622 -10.1092 180)
			(unlocked yes)
			(layer "F.Fab")
			(hide yes)
			(effects
				(font
					(size 1.016 1.016)
					(thickness 0.1524)
				)
			)
		)
		(duplicate_pad_numbers_are_jumpers no)
		(fp_line
			(start 1.4478 1.7018)
			(end 1.4478 -1.7018)
			(stroke
				(width 0.1524)
				(type default)
			)
			(layer "F.SilkS")
		)
		(fp_line
			(start 1.4478 -1.7018)
			(end -1.4478 -1.7018)
			(stroke
				(width 0.1524)
				(type default)
			)
			(layer "F.SilkS")
		)
		(fp_line
			(start -1.27 1.524)
			(end -1.27 0.6604)
			(stroke
				(width 0.4826)
				(type default)
			)
			(layer "F.SilkS")
		)
		(fp_line
			(start -1.4478 1.7018)
			(end 1.4478 1.7018)
			(stroke
				(width 0.1524)
				(type default)
			)
			(layer "F.SilkS")
		)
		(fp_line
			(start -1.4478 -1.7018)
			(end -1.4478 1.7018)
			(stroke
				(width 0.1524)
				(type default)
			)
			(layer "F.SilkS")
		)
		(fp_poly
			(pts
				(xy -1.524 -1.778) (xy 1.524 -1.778) (xy 1.524 1.778) (xy -1.524 1.778)
			)
			(stroke
				(width 0)
				(type default)
			)
			(fill no)
			(layer "F.CrtYd")
		)
		(fp_poly
			(pts
				(xy -1.524 -1.778) (xy 1.524 -1.778) (xy 1.524 1.778) (xy -1.524 1.778)
			)
			(stroke
				(width 0)
				(type default)
			)
			(fill no)
			(layer "F.Fab")
		)
		(pad "1" smd rect
			(at -0.65024 0.9398 180)
			(size 0.4064 1.016)
			(layers "F.Cu" "F.Mask" "F.Paste")
			(net "GND")
		)
		(pad "2" smd rect
			(at 0 0.9398 180)
			(size 0.4064 1.016)
			(layers "F.Cu" "F.Mask" "F.Paste")
			(net "SW_PWR_R_HDD3")
		)
		(pad "3" smd rect
			(at 0.65024 0.9398 180)
			(size 0.4064 1.016)
			(layers "F.Cu" "F.Mask" "F.Paste")
			(net "SW_HDD_P3")
		)
		(pad "4" smd rect
			(at 0.65024 -0.9398 180)
			(size 0.4064 1.016)
			(layers "F.Cu" "F.Mask" "F.Paste")
			(net "GND")
		)
		(pad "5" smd rect
			(at 0 -0.9398 180)
			(size 0.4064 1.016)
			(layers "F.Cu" "F.Mask" "F.Paste")
			(net "SW_HDD_G3")
		)
		(pad "6" smd rect
			(at -0.65024 -0.9398 180)
			(size 0.4064 1.016)
			(layers "F.Cu" "F.Mask" "F.Paste")
			(net "SW_HDD_R3")
		)
	)
	(footprint ""
		(layer "F.Cu")
		(at 312.5724 -327.858882)
		(property "Reference" "R158"
			(at 0 0 0)
			(layer "F.SilkS")
			(hide yes)
			(effects
				(font
					(size 1.27 1.27)
				)
			)
		)
		(property "Value" "100KR2F-L1-GP"
			(at 0.064008 -3.993896 0)
			(unlocked yes)
			(layer "F.Fab")
			(hide yes)
			(effects
				(font
					(size 1.016 1.016)
					(thickness 0.1524)
				)
			)
		)
		(property "Device Type" "R402H16"
			(at 0.064008 -5.517896 0)
			(unlocked yes)
			(layer "F.Fab")
			(hide yes)
			(effects
				(font
					(size 1.016 1.016)
					(thickness 0.1524)
				)
			)
		)
		(duplicate_pad_numbers_are_jumpers no)
		(fp_line
			(start -0.508 -0.9398)
			(end -0.508 0.9398)
			(stroke
				(width 0.1524)
				(type default)
			)
			(layer "F.SilkS")
		)
		(fp_line
			(start 0.508 -0.9398)
			(end -0.508 -0.9398)
			(stroke
				(width 0.1524)
				(type default)
			)
			(layer "F.SilkS")
		)
		(fp_rect
			(start -0.508 0.9398)
			(end 0.508 -0.9398)
			(stroke
				(width 0)
				(type default)
			)
			(fill no)
			(layer "F.CrtYd")
		)
		(fp_rect
			(start -0.508 0.9398)
			(end 0.508 -0.9398)
			(stroke
				(width 0)
				(type default)
			)
			(fill no)
			(layer "F.Fab")
		)
		(pad "1" smd custom
			(at 0 -0.4445)
			(size 0.1397 0.1397)
			(layers "F.Cu" "F.Mask" "F.Paste")
			(net "PWM_BMC_A_ZONE_D")
			(options
				(clearance outline)
				(anchor circle)
			)
			(primitives
				(gr_poly
					(pts
						(arc
							(start -0.1778 -0.2794)
							(mid -0.249642 -0.249642)
							(end -0.2794 -0.1778)
						)
						(arc
							(start -0.2794 0.1778)
							(mid -0.249642 0.249642)
							(end -0.1778 0.2794)
						)
						(arc
							(start 0.1778 0.2794)
							(mid 0.249642 0.249642)
							(end 0.2794 0.1778)
						)
						(arc
							(start 0.2794 -0.1778)
							(mid 0.249642 -0.249642)
							(end 0.1778 -0.2794)
						)
					)
					(width 0)
					(fill yes)
				)
			)
		)
		(pad "2" smd custom
			(at 0 0.4445)
			(size 0.1397 0.1397)
			(layers "F.Cu" "F.Mask" "F.Paste")
			(net "GND")
			(options
				(clearance outline)
				(anchor circle)
			)
			(primitives
				(gr_poly
					(pts
						(arc
							(start -0.1778 -0.2794)
							(mid -0.249642 -0.249642)
							(end -0.2794 -0.1778)
						)
						(arc
							(start -0.2794 0.1778)
							(mid -0.249642 0.249642)
							(end -0.1778 0.2794)
						)
						(arc
							(start 0.1778 0.2794)
							(mid 0.249642 0.249642)
							(end 0.2794 0.1778)
						)
						(arc
							(start 0.2794 -0.1778)
							(mid 0.249642 -0.249642)
							(end 0.1778 -0.2794)
						)
					)
					(width 0)
					(fill yes)
				)
			)
		)
	)
	(footprint ""
		(layer "F.Cu")
		(at 321.6656 -261.62)
		(property "Reference" "C115"
			(at 0 0 0)
			(layer "F.SilkS")
			(hide yes)
			(effects
				(font
					(size 1.27 1.27)
				)
			)
		)
		(property "Value" "SCD01U50V2KX-1GP"
			(at 1.1811 -2.7051 0)
			(unlocked yes)
			(layer "F.Fab")
			(hide yes)
			(effects
				(font
					(size 1.016 1.016)
					(thickness 0.1524)
				)
			)
		)
		(property "Device Type" "C402H22"
			(at 1.1811 -4.2291 0)
			(unlocked yes)
			(layer "F.Fab")
			(hide yes)
			(effects
				(font
					(size 1.016 1.016)
					(thickness 0.1524)
				)
			)
		)
		(duplicate_pad_numbers_are_jumpers no)
		(fp_rect
			(start -0.4318 0.9525)
			(end 0.4318 -0.9525)
			(stroke
				(width 0)
				(type default)
			)
			(fill no)
			(layer "F.CrtYd")
		)
		(fp_rect
			(start -0.4318 0.9525)
			(end 0.4318 -0.9525)
			(stroke
				(width 0)
				(type default)
			)
			(fill no)
			(layer "F.Fab")
		)
		(pad "1" smd custom
			(at 0 -0.4445)
			(size 0.1524 0.1524)
			(layers "F.Cu" "F.Mask" "F.Paste")
			(net "HDD_PRSNT_6")
			(options
				(clearance outline)
				(anchor circle)
			)
			(primitives
				(gr_poly
					(pts
						(arc
							(start 0.3048 -0.2032)
							(mid 0.275042 -0.275042)
							(end 0.2032 -0.3048)
						)
						(arc
							(start -0.2032 -0.3048)
							(mid -0.275042 -0.275042)
							(end -0.3048 -0.2032)
						)
						(arc
							(start -0.3048 0.2032)
							(mid -0.275042 0.275042)
							(end -0.2032 0.3048)
						)
						(arc
							(start 0.2032 0.3048)
							(mid 0.275042 0.275042)
							(end 0.3048 0.2032)
						)
					)
					(width 0)
					(fill yes)
				)
			)
		)
		(pad "2" smd custom
			(at 0 0.4445)
			(size 0.1524 0.1524)
			(layers "F.Cu" "F.Mask" "F.Paste")
			(net "GND")
			(options
				(clearance outline)
				(anchor circle)
			)
			(primitives
				(gr_poly
					(pts
						(arc
							(start 0.3048 -0.2032)
							(mid 0.275042 -0.275042)
							(end 0.2032 -0.3048)
						)
						(arc
							(start -0.2032 -0.3048)
							(mid -0.275042 -0.275042)
							(end -0.3048 -0.2032)
						)
						(arc
							(start -0.3048 0.2032)
							(mid -0.275042 0.275042)
							(end -0.2032 0.3048)
						)
						(arc
							(start 0.2032 0.3048)
							(mid 0.275042 0.275042)
							(end 0.3048 0.2032)
						)
					)
					(width 0)
					(fill yes)
				)
			)
		)
	)
	(footprint ""
		(layer "F.Cu")
		(at 52.285646 -118.316756 -90)
		(property "Reference" "R1121"
			(at 0 0 270)
			(layer "F.SilkS")
			(hide yes)
			(effects
				(font
					(size 1.27 1.27)
				)
			)
		)
		(property "Value" "10KR2F-2-GP"
			(at 0.064008 -3.993896 270)
			(unlocked yes)
			(layer "F.Fab")
			(hide yes)
			(effects
				(font
					(size 1.016 1.016)
					(thickness 0.1524)
				)
			)
		)
		(property "Device Type" "R402H16"
			(at 0.064008 -5.517896 270)
			(unlocked yes)
			(layer "F.Fab")
			(hide yes)
			(effects
				(font
					(size 1.016 1.016)
					(thickness 0.1524)
				)
			)
		)
		(duplicate_pad_numbers_are_jumpers no)
		(fp_line
			(start -0.508 -0.9398)
			(end -0.508 0.9398)
			(stroke
				(width 0.1524)
				(type default)
			)
			(layer "F.SilkS")
		)
		(fp_line
			(start 0.508 -0.9398)
			(end -0.508 -0.9398)
			(stroke
				(width 0.1524)
				(type default)
			)
			(layer "F.SilkS")
		)
		(fp_rect
			(start -0.508 0.9398)
			(end 0.508 -0.9398)
			(stroke
				(width 0)
				(type default)
			)
			(fill no)
			(layer "F.CrtYd")
		)
		(fp_rect
			(start -0.508 0.9398)
			(end 0.508 -0.9398)
			(stroke
				(width 0)
				(type default)
			)
			(fill no)
			(layer "F.Fab")
		)
		(pad "1" smd custom
			(at 0 -0.4445 270)
			(size 0.1397 0.1397)
			(layers "F.Cu" "F.Mask" "F.Paste")
			(net "P5V_B_2")
			(options
				(clearance outline)
				(anchor circle)
			)
			(primitives
				(gr_poly
					(pts
						(arc
							(start -0.1778 -0.2794)
							(mid -0.249642 -0.249642)
							(end -0.2794 -0.1778)
						)
						(arc
							(start -0.2794 0.1778)
							(mid -0.249642 0.249642)
							(end -0.1778 0.2794)
						)
						(arc
							(start 0.1778 0.2794)
							(mid 0.249642 0.249642)
							(end 0.2794 0.1778)
						)
						(arc
							(start 0.2794 -0.1778)
							(mid 0.249642 -0.249642)
							(end 0.1778 -0.2794)
						)
					)
					(width 0)
					(fill yes)
				)
			)
		)
		(pad "2" smd custom
			(at 0 0.4445 270)
			(size 0.1397 0.1397)
			(layers "F.Cu" "F.Mask" "F.Paste")
			(net "P5V_B_2_PGOOD")
			(options
				(clearance outline)
				(anchor circle)
			)
			(primitives
				(gr_poly
					(pts
						(arc
							(start -0.1778 -0.2794)
							(mid -0.249642 -0.249642)
							(end -0.2794 -0.1778)
						)
						(arc
							(start -0.2794 0.1778)
							(mid -0.249642 0.249642)
							(end -0.1778 0.2794)
						)
						(arc
							(start 0.1778 0.2794)
							(mid 0.249642 0.249642)
							(end 0.2794 0.1778)
						)
						(arc
							(start 0.2794 -0.1778)
							(mid 0.249642 -0.249642)
							(end 0.1778 -0.2794)
						)
					)
					(width 0)
					(fill yes)
				)
			)
		)
	)
)
